# T6G (Grand Teton) — schematic netlist excerpt (pin names and nets, part order shuffled) for the footprints in the layout excerpt that follows; sources: Cadence DE-HDL packaged netlist, KiCad conversion of 04192023_DAF0TMB3IC0_F0TG_MB_C_brd_V02_OCP.brd

R6267  Q_RES  0 5% CHIP  pkg 0402LF  page 179 : A = USB_HUB2_TI_VDD_MRP_USB3DN_TXDP4 ; B = P1V2_CPU0_USB2_DVDD12
R6205  Q_RES  10K 1% CHIP  pkg 0402LF  page 176 : A = P3V3_AUX ; B = PU_CPU0_USB_HUB_OVRCURR

(kicad_pcb
	(version 20260206)
	(generator "pcbnew")
	(generator_version "10.0")
	(general
		(thickness 1.6)
		(legacy_teardrops no)
	)
	(paper "A4")
	(title_block
		(title "04192023_DAF0TMB3IC0_F0TG_MB_C_brd_V02_OCP.brd")
		(comment 1 "Grand Teton / footprints 3162-3163 of 8354")
	)
	(layers
		(0 "F.Cu" signal "TOP")
		(4 "In1.Cu" signal "GND")
		(6 "In2.Cu" signal "IN1")
		(8 "In3.Cu" signal "GND1")
		(10 "In4.Cu" signal "IN2")
		(12 "In5.Cu" signal "GND2")
		(14 "In6.Cu" signal "IN3")
		(16 "In7.Cu" signal "GND3")
		(18 "In8.Cu" signal "VCC")
		(20 "In9.Cu" signal "VCC1")
		(22 "In10.Cu" signal "GND4")
		(24 "In11.Cu" signal "IN4")
		(26 "In12.Cu" signal "GND5")
		(28 "In13.Cu" signal "IN5")
		(30 "In14.Cu" signal "GND6")
		(32 "In15.Cu" signal "IN6")
		(34 "In16.Cu" signal "GND7")
		(2 "B.Cu" signal "BOTTOM")
		(9 "F.Adhes" user "F.Adhesive")
		(11 "B.Adhes" user "B.Adhesive")
		(13 "F.Paste" user "Package Geometry/Pastemask Top")
		(15 "B.Paste" user "Package Geometry/Pastemask Bottom")
		(5 "F.SilkS" user "Ref Des/Silkscreen Top")
		(7 "B.SilkS" user "Ref Des/Silkscreen Bottom")
		(1 "F.Mask" user "Board Geometry/Soldermask Top")
		(3 "B.Mask" user "Board Geometry/Soldermask Bottom")
		(17 "Dwgs.User" user "User.Drawings")
		(19 "Cmts.User" user "User.Comments")
		(21 "Eco1.User" user "User.Eco1")
		(23 "Eco2.User" user "User.Eco2")
		(25 "Edge.Cuts" user "Board Geometry/Outline")
		(27 "Margin" user)
		(31 "F.CrtYd" user "Package Geometry/Place Bound Top")
		(29 "B.CrtYd" user "Package Geometry/Place Bound Bottom")
		(35 "F.Fab" user "Ref Des/Assembly Top")
		(33 "B.Fab" user "Ref Des/Assembly Bottom")
	)
	(footprint ""
		(layer "F.Cu")
		(at 120.69826 -29.373576)
		(property "Reference" "R6267"
			(at 0 0 0)
			(layer "F.SilkS")
			(hide yes)
			(effects
				(font
					(size 1.27 1.27)
				)
			)
		)
		(property "Value" ""
			(at 0 0 0)
			(layer "F.Fab")
			(effects
				(font
					(size 1.27 1.27)
				)
			)
		)
		(duplicate_pad_numbers_are_jumpers no)
		(fp_line
			(start -0.7874 -0.4064)
			(end 0.7874 -0.4064)
			(stroke
				(width 0.1524)
				(type default)
			)
			(layer "F.SilkS")
		)
		(fp_line
			(start -0.7874 0.4064)
			(end -0.7874 -0.4064)
			(stroke
				(width 0.1524)
				(type default)
			)
			(layer "F.SilkS")
		)
		(fp_line
			(start 0.7874 -0.4064)
			(end 0.7874 0.4064)
			(stroke
				(width 0.1524)
				(type default)
			)
			(layer "F.SilkS")
		)
		(fp_line
			(start 0.7874 0.4064)
			(end -0.7874 0.4064)
			(stroke
				(width 0.1524)
				(type default)
			)
			(layer "F.SilkS")
		)
		(fp_line
			(start -0.67945 -0.305054)
			(end -0.12065 -0.305054)
			(stroke
				(width 0.1)
				(type default)
			)
			(layer "F.Fab")
		)
		(fp_line
			(start -0.67945 0.3048)
			(end -0.67945 -0.305054)
			(stroke
				(width 0.1)
				(type default)
			)
			(layer "F.Fab")
		)
		(fp_line
			(start -0.12065 -0.305054)
			(end -0.12065 -0.2794)
			(stroke
				(width 0.1)
				(type default)
			)
			(layer "F.Fab")
		)
		(fp_line
			(start -0.12065 -0.2794)
			(end 0.12065 -0.2794)
			(stroke
				(width 0.1)
				(type default)
			)
			(layer "F.Fab")
		)
		(fp_line
			(start -0.12065 0.2794)
			(end -0.12065 0.3048)
			(stroke
				(width 0.1)
				(type default)
			)
			(layer "F.Fab")
		)
		(fp_line
			(start -0.12065 0.3048)
			(end -0.67945 0.3048)
			(stroke
				(width 0.1)
				(type default)
			)
			(layer "F.Fab")
		)
		(fp_line
			(start 0.120396 0.2794)
			(end -0.12065 0.2794)
			(stroke
				(width 0.1)
				(type default)
			)
			(layer "F.Fab")
		)
		(fp_line
			(start 0.120396 0.3048)
			(end 0.120396 0.2794)
			(stroke
				(width 0.1)
				(type default)
			)
			(layer "F.Fab")
		)
		(fp_line
			(start 0.12065 -0.3048)
			(end 0.67945 -0.3048)
			(stroke
				(width 0.1)
				(type default)
			)
			(layer "F.Fab")
		)
		(fp_line
			(start 0.12065 -0.2794)
			(end 0.12065 -0.3048)
			(stroke
				(width 0.1)
				(type default)
			)
			(layer "F.Fab")
		)
		(fp_line
			(start 0.67945 -0.3048)
			(end 0.67945 0.3048)
			(stroke
				(width 0.1)
				(type default)
			)
			(layer "F.Fab")
		)
		(fp_line
			(start 0.67945 0.3048)
			(end 0.120396 0.3048)
			(stroke
				(width 0.1)
				(type default)
			)
			(layer "F.Fab")
		)
		(pad "1" smd circle
			(at -0.40005 0)
			(size 0 0)
			(layers "F.Cu" "F.Mask" "F.Paste")
			(net "USB_HUB2_TI_VDD_MRP_USB3DN_TXDP4")
		)
		(pad "2" smd circle
			(at 0.40005 0)
			(size 0 0)
			(layers "F.Cu" "F.Mask" "F.Paste")
			(net "P1V2_CPU0_USB2_DVDD12")
		)
	)
	(footprint ""
		(layer "F.Cu")
		(at 126.804928 -47.121064)
		(property "Reference" "R6205"
			(at 0 0 0)
			(layer "F.SilkS")
			(hide yes)
			(effects
				(font
					(size 1.27 1.27)
				)
			)
		)
		(property "Value" ""
			(at 0 0 0)
			(layer "F.Fab")
			(effects
				(font
					(size 1.27 1.27)
				)
			)
		)
		(duplicate_pad_numbers_are_jumpers no)
		(fp_line
			(start -0.7874 -0.4064)
			(end 0.7874 -0.4064)
			(stroke
				(width 0.1524)
				(type default)
			)
			(layer "F.SilkS")
		)
		(fp_line
			(start -0.7874 0.4064)
			(end -0.7874 -0.4064)
			(stroke
				(width 0.1524)
				(type default)
			)
			(layer "F.SilkS")
		)
		(fp_line
			(start 0.7874 -0.4064)
			(end 0.7874 0.4064)
			(stroke
				(width 0.1524)
				(type default)
			)
			(layer "F.SilkS")
		)
		(fp_line
			(start 0.7874 0.4064)
			(end -0.7874 0.4064)
			(stroke
				(width 0.1524)
				(type default)
			)
			(layer "F.SilkS")
		)
		(fp_line
			(start -0.67945 -0.305054)
			(end -0.12065 -0.305054)
			(stroke
				(width 0.1)
				(type default)
			)
			(layer "F.Fab")
		)
		(fp_line
			(start -0.67945 0.3048)
			(end -0.67945 -0.305054)
			(stroke
				(width 0.1)
				(type default)
			)
			(layer "F.Fab")
		)
		(fp_line
			(start -0.12065 -0.305054)
			(end -0.12065 -0.2794)
			(stroke
				(width 0.1)
				(type default)
			)
			(layer "F.Fab")
		)
		(fp_line
			(start -0.12065 -0.2794)
			(end 0.12065 -0.2794)
			(stroke
				(width 0.1)
				(type default)
			)
			(layer "F.Fab")
		)
		(fp_line
			(start -0.12065 0.2794)
			(end -0.12065 0.3048)
			(stroke
				(width 0.1)
				(type default)
			)
			(layer "F.Fab")
		)
		(fp_line
			(start -0.12065 0.3048)
			(end -0.67945 0.3048)
			(stroke
				(width 0.1)
				(type default)
			)
			(layer "F.Fab")
		)
		(fp_line
			(start 0.120396 0.2794)
			(end -0.12065 0.2794)
			(stroke
				(width 0.1)
				(type default)
			)
			(layer "F.Fab")
		)
		(fp_line
			(start 0.120396 0.3048)
			(end 0.120396 0.2794)
			(stroke
				(width 0.1)
				(type default)
			)
			(layer "F.Fab")
		)
		(fp_line
			(start 0.12065 -0.3048)
			(end 0.67945 -0.3048)
			(stroke
				(width 0.1)
				(type default)
			)
			(layer "F.Fab")
		)
		(fp_line
			(start 0.12065 -0.2794)
			(end 0.12065 -0.3048)
			(stroke
				(width 0.1)
				(type default)
			)
			(layer "F.Fab")
		)
		(fp_line
			(start 0.67945 -0.3048)
			(end 0.67945 0.3048)
			(stroke
				(width 0.1)
				(type default)
			)
			(layer "F.Fab")
		)
		(fp_line
			(start 0.67945 0.3048)
			(end 0.120396 0.3048)
			(stroke
				(width 0.1)
				(type default)
			)
			(layer "F.Fab")
		)
		(pad "1" smd circle
			(at -0.40005 0)
			(size 0 0)
			(layers "F.Cu" "F.Mask" "F.Paste")
			(net "P3V3_AUX")
		)
		(pad "2" smd circle
			(at 0.40005 0)
			(size 0 0)
			(layers "F.Cu" "F.Mask" "F.Paste")
			(net "PU_CPU0_USB_HUB_OVRCURR")
		)
	)
)
